(kicad_pcb
	(version 20260206)
	(generator "pcbnew")
	(generator_version "10.0")
	(general
		(thickness 1.6)
		(legacy_teardrops no)
	)
	(paper "A4")
	(title_block
		(title "v1-chassis-manager — T6M_CM_d_v01_1031_1645.brd")
		(comment 1 "Open CloudServer (Microsoft) / footprints 184-185 of 2512")
	)
	(layers
		(0 "F.Cu" signal "TOP")
		(4 "In1.Cu" signal "GND1")
		(6 "In2.Cu" signal "IN1")
		(8 "In3.Cu" signal "VCC1")
		(10 "In4.Cu" signal "VCC2")
		(12 "In5.Cu" signal "GND2")
		(14 "In6.Cu" signal "IN2")
		(16 "In7.Cu" signal "IN3")
		(18 "In8.Cu" signal "GND3")
		(2 "B.Cu" signal "BOTTOM")
		(9 "F.Adhes" user "F.Adhesive")
		(11 "B.Adhes" user "B.Adhesive")
		(13 "F.Paste" user "Package Geometry/Pastemask Top")
		(15 "B.Paste" user "Package Geometry/Pastemask Bottom")
		(5 "F.SilkS" user "Ref Des/Silkscreen Top")
		(7 "B.SilkS" user "Ref Des/Silkscreen Bottom")
		(1 "F.Mask" user "Board Geometry/Soldermask Top")
		(3 "B.Mask" user "Board Geometry/Soldermask Bottom")
		(17 "Dwgs.User" user "User.Drawings")
		(19 "Cmts.User" user "User.Comments")
		(21 "Eco1.User" user "User.Eco1")
		(23 "Eco2.User" user "User.Eco2")
		(25 "Edge.Cuts" user "Board Geometry/Outline")
		(27 "Margin" user)
		(31 "F.CrtYd" user "Package Geometry/Place Bound Top")
		(29 "B.CrtYd" user "Package Geometry/Place Bound Bottom")
		(35 "F.Fab" user "Ref Des/Assembly Top")
		(33 "B.Fab" user "Ref Des/Assembly Bottom")
	)
	(footprint ""
		(layer "F.Cu")
		(at 107.595924 -69.156326 -90)
		(property "Reference" "J3"
			(at -11.305286 0.945388 0)
			(unlocked yes)
			(layer "F.SilkS")
			(effects
				(font
					(size 0.7874 0.5842)
					(thickness 0.1524)
				)
				(justify left)
			)
		)
		(property "Value" ""
			(at 0 0 270)
			(layer "F.Fab")
			(effects
				(font
					(size 1.27 1.27)
				)
			)
		)
		(duplicate_pad_numbers_are_jumpers no)
		(fp_line
			(start -10.661396 3.6195)
			(end -10.661396 -1.888744)
			(stroke
				(width 0.1524)
				(type default)
			)
			(layer "F.SilkS")
		)
		(fp_line
			(start -7.719822 3.6195)
			(end -10.661396 3.6195)
			(stroke
				(width 0.1524)
				(type default)
			)
			(layer "F.SilkS")
		)
		(fp_line
			(start 10.638536 3.6195)
			(end 7.720076 3.6195)
			(stroke
				(width 0.1524)
				(type default)
			)
			(layer "F.SilkS")
		)
		(fp_line
			(start 10.638536 -1.913128)
			(end 10.638536 3.6195)
			(stroke
				(width 0.1524)
				(type default)
			)
			(layer "F.SilkS")
		)
		(fp_line
			(start -10.661396 -3.6195)
			(end -7.719822 -3.6195)
			(stroke
				(width 0.1524)
				(type default)
			)
			(layer "F.SilkS")
		)
		(fp_line
			(start 7.720076 -3.6195)
			(end 10.638536 -3.6195)
			(stroke
				(width 0.1524)
				(type default)
			)
			(layer "F.SilkS")
		)
		(fp_poly
			(pts
				(xy -7.249922 4.197604) (xy -7.630922 5.340604) (xy -6.868922 5.340604)
			)
			(stroke
				(width 0)
				(type default)
			)
			(fill yes)
			(layer "F.SilkS")
		)
		(fp_poly
			(pts
				(arc
					(start 10.072878 -3.460496)
					(mid 9.498142 -3.222432)
					(end 9.260078 -2.647696)
				)
				(arc
					(start 9.260078 -2.647696)
					(mid 9.490702 -2.09092)
					(end 10.047478 -1.860296)
				)
				(arc
					(start 10.072878 -1.860296)
					(mid 10.872978 -2.660396)
					(end 10.072878 -3.460496)
				)
			)
			(stroke
				(width 0)
				(type default)
			)
			(fill no)
			(layer "B.CrtYd")
		)
		(fp_poly
			(pts
				(arc
					(start -10.069322 -3.460496)
					(mid -10.626098 -3.229872)
					(end -10.856722 -2.673096)
				)
				(arc
					(start -10.856722 -2.647696)
					(mid -10.626098 -2.09092)
					(end -10.069322 -1.860296)
				)
				(arc
					(start -10.043922 -1.860296)
					(mid -9.243822 -2.660396)
					(end -10.043922 -3.460496)
				)
			)
			(stroke
				(width 0)
				(type default)
			)
			(fill no)
			(layer "B.CrtYd")
		)
		(fp_poly
			(pts
				(xy -10.661396 -3.6195) (xy -7.427722 -3.6195) (xy -7.427722 -4.044696) (xy 7.431278 -4.044696)
				(xy 7.431278 -3.6195) (xy 10.638536 -3.6195) (xy 10.827004 -3.6195) (xy 10.827004 3.621024) (xy 10.638536 3.621024)
				(xy 10.638536 3.6195) (xy 7.431278 3.6195) (xy 7.431278 4.032504) (xy -7.427722 4.032504) (xy -7.427722 3.6195)
				(xy -10.661396 3.6195) (xy -10.671302 3.6195) (xy -10.81151 3.6195) (xy -10.81151 -3.6195) (xy -10.671302 -3.6195)
			)
			(stroke
				(width 0)
				(type default)
			)
			(fill no)
			(layer "F.CrtYd")
		)
		(fp_line
			(start -10.661396 3.6195)
			(end 10.638536 3.6195)
			(stroke
				(width 0.1)
				(type default)
			)
			(layer "F.Fab")
		)
		(fp_line
			(start 10.638536 3.6195)
			(end 10.638536 -3.6195)
			(stroke
				(width 0.1)
				(type default)
			)
			(layer "F.Fab")
		)
		(fp_line
			(start -10.661396 -3.6195)
			(end -10.661396 3.6195)
			(stroke
				(width 0.1)
				(type default)
			)
			(layer "F.Fab")
		)
		(fp_line
			(start 10.638536 -3.6195)
			(end -10.661396 -3.6195)
			(stroke
				(width 0.1)
				(type default)
			)
			(layer "F.Fab")
		)
		(fp_text user "59"
			(at 9.438386 5.19938 0)
			(unlocked yes)
			(layer "F.SilkS")
			(effects
				(font
					(size 0.635 0.4064)
					(thickness 0.1524)
				)
				(justify left)
			)
		)
		(fp_text user "1"
			(at -7.9756 4.418584 0)
			(unlocked yes)
			(layer "F.SilkS")
			(effects
				(font
					(size 0.635 0.4064)
					(thickness 0.1524)
				)
				(justify left)
			)
		)
		(fp_text user "60"
			(at 10.22096 -3.782314 0)
			(unlocked yes)
			(layer "F.SilkS")
			(effects
				(font
					(size 0.635 0.4064)
					(thickness 0.1524)
				)
				(justify left)
			)
		)
		(fp_text user "2"
			(at -8.030718 -4.084828 0)
			(unlocked yes)
			(layer "F.SilkS")
			(effects
				(font
					(size 0.635 0.4064)
					(thickness 0.1524)
				)
				(justify left)
			)
		)
		(fp_text user "59"
			(at 7.1628 4.708906 270)
			(unlocked yes)
			(layer "F.Fab")
			(effects
				(font
					(size 0.7874 0.5842)
					(thickness 0.000001)
				)
				(justify left)
			)
		)
		(fp_text user "1"
			(at -8.1153 4.327906 270)
			(unlocked yes)
			(layer "F.Fab")
			(effects
				(font
					(size 0.7874 0.5842)
					(thickness 0.000001)
				)
				(justify left)
			)
		)
		(fp_text user "2"
			(at -8.1915 -4.536694 270)
			(unlocked yes)
			(layer "F.Fab")
			(effects
				(font
					(size 0.7874 0.5842)
					(thickness 0.000001)
				)
				(justify left)
			)
		)
		(fp_text user "60"
			(at 7.2136 -4.562094 270)
			(unlocked yes)
			(layer "F.Fab")
			(effects
				(font
					(size 0.7874 0.5842)
					(thickness 0.000001)
				)
				(justify left)
			)
		)
		(pad "" np_thru_hole circle
			(at -10.059924 -2.665984)
			(size 0.254 0.254)
			(drill 1.1938)
			(layers "*.Cu" "*.Mask")
			(clearance 0.8509)
			(thermal_gap 0.8509)
		)
		(pad "" np_thru_hole circle
			(at 10.065766 -2.665984)
			(size 0.254 0.254)
			(drill 1.1938)
			(layers "*.Cu" "*.Mask")
			(clearance 0.8509)
			(thermal_gap 0.8509)
		)
		(pad "1" smd rect
			(at -7.249922 2.864104)
			(size 2.286 0.2794)
			(layers "F.Cu" "F.Mask" "F.Paste")
			(net "GND")
		)
		(pad "2" smd rect
			(at -7.249922 -2.864104)
			(size 2.286 0.2794)
			(layers "F.Cu" "F.Mask" "F.Paste")
			(net "GND")
		)
		(pad "3" smd rect
			(at -6.749796 2.864104)
			(size 2.286 0.2794)
			(layers "F.Cu" "F.Mask" "F.Paste")
			(net "XDP_CPU_NODE1_PREQ_L")
		)
		(pad "4" smd rect
			(at -6.749796 -2.864104)
			(size 2.286 0.2794)
			(layers "F.Cu" "F.Mask" "F.Paste")
			(net "XDP_CPU_NODE1_VISA0")
		)
		(pad "5" smd rect
			(at -6.249924 2.864104)
			(size 2.286 0.2794)
			(layers "F.Cu" "F.Mask" "F.Paste")
			(net "XDP_CPU_NODE1_PRDY_L")
		)
		(pad "6" smd rect
			(at -6.249924 -2.864104)
			(size 2.286 0.2794)
			(layers "F.Cu" "F.Mask" "F.Paste")
			(net "XDP_CPU_NODE1_VISA9")
		)
		(pad "7" smd rect
			(at -5.749798 2.864104)
			(size 2.286 0.2794)
			(layers "F.Cu" "F.Mask" "F.Paste")
			(net "GND")
		)
		(pad "8" smd rect
			(at -5.749798 -2.864104)
			(size 2.286 0.2794)
			(layers "F.Cu" "F.Mask" "F.Paste")
			(net "GND")
		)
		(pad "9" smd rect
			(at -5.249926 2.864104)
			(size 2.286 0.2794)
			(layers "F.Cu" "F.Mask" "F.Paste")
			(net "XDP_CPU_NODE1_VISA1")
		)
		(pad "10" smd rect
			(at -5.249926 -2.864104)
			(size 2.286 0.2794)
			(layers "F.Cu" "F.Mask" "F.Paste")
			(net "XDP_CPU_NODE1_VISA10")
		)
		(pad "11" smd rect
			(at -4.7498 2.864104)
			(size 2.286 0.2794)
			(layers "F.Cu" "F.Mask" "F.Paste")
			(net "XDP_CPU_NODE1_VISA2")
		)
		(pad "12" smd rect
			(at -4.7498 -2.864104)
			(size 2.286 0.2794)
			(layers "F.Cu" "F.Mask" "F.Paste")
			(net "XDP_CPU_NODE1_VISA11")
		)
		(pad "13" smd rect
			(at -4.249928 2.864104)
			(size 2.286 0.2794)
			(layers "F.Cu" "F.Mask" "F.Paste")
			(net "GND")
		)
		(pad "14" smd rect
			(at -4.249928 -2.864104)
			(size 2.286 0.2794)
			(layers "F.Cu" "F.Mask" "F.Paste")
			(net "GND")
		)
		(pad "15" smd rect
			(at -3.749802 2.864104)
			(size 2.286 0.2794)
			(layers "F.Cu" "F.Mask" "F.Paste")
			(net "XDP_CPU_NODE1_VISA3")
		)
		(pad "16" smd rect
			(at -3.749802 -2.864104)
			(size 2.286 0.2794)
			(layers "F.Cu" "F.Mask" "F.Paste")
			(net "XDP_CPU_NODE1_VISA12")
		)
		(pad "17" smd rect
			(at -3.24993 2.864104)
			(size 2.286 0.2794)
			(layers "F.Cu" "F.Mask" "F.Paste")
			(net "XDP_CPU_NODE1_VISA4")
		)
		(pad "18" smd rect
			(at -3.24993 -2.864104)
			(size 2.286 0.2794)
			(layers "F.Cu" "F.Mask" "F.Paste")
			(net "XDP_CPU_NODE1_VISA13")
		)
		(pad "19" smd rect
			(at -2.749804 2.864104)
			(size 2.286 0.2794)
			(layers "F.Cu" "F.Mask" "F.Paste")
			(net "GND")
		)
		(pad "20" smd rect
			(at -2.749804 -2.864104)
			(size 2.286 0.2794)
			(layers "F.Cu" "F.Mask" "F.Paste")
			(net "GND")
		)
		(pad "21" smd rect
			(at -2.249932 2.864104)
			(size 2.286 0.2794)
			(layers "F.Cu" "F.Mask" "F.Paste")
			(net "Net_1687")
		)
		(pad "22" smd rect
			(at -2.249932 -2.864104)
			(size 2.286 0.2794)
			(layers "F.Cu" "F.Mask" "F.Paste")
			(net "Net_1688")
		)
		(pad "23" smd rect
			(at -1.749806 2.864104)
			(size 2.286 0.2794)
			(layers "F.Cu" "F.Mask" "F.Paste")
			(net "Net_1689")
		)
		(pad "24" smd rect
			(at -1.749806 -2.864104)
			(size 2.286 0.2794)
			(layers "F.Cu" "F.Mask" "F.Paste")
			(net "Net_1690")
		)
		(pad "25" smd rect
			(at -1.249934 2.864104)
			(size 2.286 0.2794)
			(layers "F.Cu" "F.Mask" "F.Paste")
			(net "GND")
		)
		(pad "26" smd rect
			(at -1.249934 -2.864104)
			(size 2.286 0.2794)
			(layers "F.Cu" "F.Mask" "F.Paste")
			(net "GND")
		)
		(pad "27" smd rect
			(at -0.750062 2.864104)
			(size 2.286 0.2794)
			(layers "F.Cu" "F.Mask" "F.Paste")
			(net "XDP_CPU_NODE1_VISA5")
		)
		(pad "28" smd rect
			(at -0.750062 -2.864104)
			(size 2.286 0.2794)
			(layers "F.Cu" "F.Mask" "F.Paste")
			(net "XDP_CPU_NODE1_VISA14")
		)
		(pad "29" smd rect
			(at -0.249936 2.864104)
			(size 2.286 0.2794)
			(layers "F.Cu" "F.Mask" "F.Paste")
			(net "XDP_CPU_NODE1_VISA6")
		)
		(pad "30" smd rect
			(at -0.249936 -2.864104)
			(size 2.286 0.2794)
			(layers "F.Cu" "F.Mask" "F.Paste")
			(net "XDP_CPU_NODE1_VISA15")
		)
		(pad "31" smd rect
			(at 0.25019 2.864104)
			(size 2.286 0.2794)
			(layers "F.Cu" "F.Mask" "F.Paste")
			(net "GND")
		)
		(pad "32" smd rect
			(at 0.25019 -2.864104)
			(size 2.286 0.2794)
			(layers "F.Cu" "F.Mask" "F.Paste")
			(net "GND")
		)
		(pad "33" smd rect
			(at 0.750062 2.864104)
			(size 2.286 0.2794)
			(layers "F.Cu" "F.Mask" "F.Paste")
			(net "XDP_CPU_NODE1_VISA7")
		)
		(pad "34" smd rect
			(at 0.750062 -2.864104)
			(size 2.286 0.2794)
			(layers "F.Cu" "F.Mask" "F.Paste")
			(net "XDP_CPU_NODE1_VISA16")
		)
		(pad "35" smd rect
			(at 1.250188 2.864104)
			(size 2.286 0.2794)
			(layers "F.Cu" "F.Mask" "F.Paste")
			(net "XDP_CPU_NODE1_VISA8")
		)
		(pad "36" smd rect
			(at 1.250188 -2.864104)
			(size 2.286 0.2794)
			(layers "F.Cu" "F.Mask" "F.Paste")
			(net "XDP_CPU_NODE1_VISA17")
		)
		(pad "37" smd rect
			(at 1.75006 2.864104)
			(size 2.286 0.2794)
			(layers "F.Cu" "F.Mask" "F.Paste")
			(net "GND")
		)
		(pad "38" smd rect
			(at 1.75006 -2.864104)
			(size 2.286 0.2794)
			(layers "F.Cu" "F.Mask" "F.Paste")
			(net "GND")
		)
		(pad "39" smd rect
			(at 2.250186 2.864104)
			(size 2.286 0.2794)
			(layers "F.Cu" "F.Mask" "F.Paste")
			(net "XDP_CPU_NODE1_PWROK_R")
		)
		(pad "40" smd rect
			(at 2.250186 -2.864104)
			(size 2.286 0.2794)
			(layers "F.Cu" "F.Mask" "F.Paste")
			(net "CLK_100M_XDP_NODE1_DP")
		)
		(pad "41" smd rect
			(at 2.750058 2.864104)
			(size 2.286 0.2794)
			(layers "F.Cu" "F.Mask" "F.Paste")
			(net "XDP_CPU_NODE1_PG_RST_R")
		)
		(pad "42" smd rect
			(at 2.750058 -2.864104)
			(size 2.286 0.2794)
			(layers "F.Cu" "F.Mask" "F.Paste")
			(net "CLK_100M_XDP_NODE1_DN")
		)
		(pad "43" smd rect
			(at 3.250184 2.864104)
			(size 2.286 0.2794)
			(layers "F.Cu" "F.Mask" "F.Paste")
			(net "P1V05_STB_NODE1_XDP_A")
		)
		(pad "44" smd rect
			(at 3.250184 -2.864104)
			(size 2.286 0.2794)
			(layers "F.Cu" "F.Mask" "F.Paste")
			(net "P1V05_STB_NODE1_XDP_B")
		)
		(pad "45" smd rect
			(at 3.750056 2.864104)
			(size 2.286 0.2794)
			(layers "F.Cu" "F.Mask" "F.Paste")
			(net "Net_1691")
		)
		(pad "46" smd rect
			(at 3.750056 -2.864104)
			(size 2.286 0.2794)
			(layers "F.Cu" "F.Mask" "F.Paste")
			(net "FM_CPLD_NODE1_CPU_RESET_L")
		)
		(pad "47" smd rect
			(at 4.249928 2.864104)
			(size 2.286 0.2794)
			(layers "F.Cu" "F.Mask" "F.Paste")
			(net "XDP_CPU_NODE1_PWROK_STALL_L")
		)
		(pad "48" smd rect
			(at 4.249928 -2.864104)
			(size 2.286 0.2794)
			(layers "F.Cu" "F.Mask" "F.Paste")
			(net "RST_NODE1_CPU_XDP_RSTIN_L")
		)
		(pad "49" smd rect
			(at 4.7498 2.864104)
			(size 2.286 0.2794)
			(layers "F.Cu" "F.Mask" "F.Paste")
			(net "GND")
		)
		(pad "50" smd rect
			(at 4.7498 -2.864104)
			(size 2.286 0.2794)
			(layers "F.Cu" "F.Mask" "F.Paste")
			(net "GND")
		)
		(pad "51" smd rect
			(at 5.25018 2.864104)
			(size 2.286 0.2794)
			(layers "F.Cu" "F.Mask" "F.Paste")
			(net "SMB_CPU_NODE1_XDP_DAT")
		)
		(pad "52" smd rect
			(at 5.25018 -2.864104)
			(size 2.286 0.2794)
			(layers "F.Cu" "F.Mask" "F.Paste")
			(net "XDP_SOC_CPU_NODE1_TDO")
		)
		(pad "53" smd rect
			(at 5.750052 2.864104)
			(size 2.286 0.2794)
			(layers "F.Cu" "F.Mask" "F.Paste")
			(net "SMB_CPU_NODE1_XDP_CLK")
		)
		(pad "54" smd rect
			(at 5.750052 -2.864104)
			(size 2.286 0.2794)
			(layers "F.Cu" "F.Mask" "F.Paste")
			(net "XDP_SOC_CPU_NODE1_TRST_L")
		)
		(pad "55" smd rect
			(at 6.250178 2.864104)
			(size 2.286 0.2794)
			(layers "F.Cu" "F.Mask" "F.Paste")
			(net "Net_1692")
		)
		(pad "56" smd rect
			(at 6.250178 -2.864104)
			(size 2.286 0.2794)
			(layers "F.Cu" "F.Mask" "F.Paste")
			(net "XDP_SOC_CPU_NODE1_TDI")
		)
		(pad "57" smd rect
			(at 6.75005 2.864104)
			(size 2.286 0.2794)
			(layers "F.Cu" "F.Mask" "F.Paste")
			(net "XDP_SOC_CPU_NODE1_TCK")
		)
		(pad "58" smd rect
			(at 6.75005 -2.864104)
			(size 2.286 0.2794)
			(layers "F.Cu" "F.Mask" "F.Paste")
			(net "XDP_SOC_CPU_NODE1_TMS")
		)
		(pad "59" smd rect
			(at 7.250176 2.864104)
			(size 2.286 0.2794)
			(layers "F.Cu" "F.Mask" "F.Paste")
			(net "GND")
		)
		(pad "60" smd rect
			(at 7.250176 -2.864104)
			(size 2.286 0.2794)
			(layers "F.Cu" "F.Mask" "F.Paste")
			(net "XDP_NODE1_P60")
		)
		(zone
			(layers "F.Cu" "B.Cu" "In1.Cu" "In2.Cu" "In3.Cu" "In4.Cu" "In5.Cu" "In6.Cu"
				"In7.Cu" "In8.Cu"
			)
			(hatch none 0.5)
			(connect_pads
				(clearance 0)
			)
			(min_thickness 0.25)
			(keepout
				(tracks not_allowed)
				(vias allowed)
				(pads allowed)
				(copperpour not_allowed)
				(footprints allowed)
			)
			(placement
				(enabled no)
				(sheetname "")
			)
			(fill
				(thermal_gap 0.5)
				(thermal_bridge_width 0.5)
				(island_removal_mode 0)
			)
			(polygon
				(pts
					(arc
						(start 109.258608 -79.21625)
						(mid 111.265716 -79.21625)
						(end 109.258608 -79.21625)
					)
				)
			)
		)
		(zone
			(layers "F.Cu" "B.Cu" "In1.Cu" "In2.Cu" "In3.Cu" "In4.Cu" "In5.Cu" "In6.Cu"
				"In7.Cu" "In8.Cu"
			)
			(hatch none 0.5)
			(connect_pads
				(clearance 0)
			)
			(min_thickness 0.25)
			(keepout
				(tracks not_allowed)
				(vias allowed)
				(pads allowed)
				(copperpour not_allowed)
				(footprints allowed)
			)
			(placement
				(enabled no)
				(sheetname "")
			)
			(fill
				(thermal_gap 0.5)
				(thermal_bridge_width 0.5)
				(island_removal_mode 0)
			)
			(polygon
				(pts
					(arc
						(start 109.258608 -59.09056)
						(mid 111.265716 -59.09056)
						(end 109.258608 -59.09056)
					)
				)
			)
		)
	)
	(footprint ""
		(layer "F.Cu")
		(at 16.718534 -49.95291 90)
		(property "Reference" "L40"
			(at -3.963924 14.24813 90)
			(unlocked yes)
			(layer "F.SilkS")
			(effects
				(font
					(size 0.7874 0.5842)
					(thickness 0.1524)
				)
			)
		)
		(property "Value" ""
			(at 0 0 90)
			(layer "F.Fab")
			(effects
				(font
					(size 1.27 1.27)
				)
			)
		)
		(duplicate_pad_numbers_are_jumpers no)
		(fp_line
			(start 1.2954 -0.635)
			(end 1.2954 0.635)
			(stroke
				(width 0.1524)
				(type default)
			)
			(layer "F.SilkS")
		)
		(fp_line
			(start -1.2954 -0.635)
			(end 1.2954 -0.635)
			(stroke
				(width 0.1524)
				(type default)
			)
			(layer "F.SilkS")
		)
		(fp_line
			(start -1.2954 -0.635)
			(end -1.2954 0.635)
			(stroke
				(width 0.1524)
				(type default)
			)
			(layer "F.SilkS")
		)
		(fp_line
			(start 0.127 -0.5842)
			(end 0.127 0.5842)
			(stroke
				(width 0.1524)
				(type default)
			)
			(layer "F.SilkS")
		)
		(fp_line
			(start -0.127 -0.5842)
			(end -0.127 0.5842)
			(stroke
				(width 0.1524)
				(type default)
			)
			(layer "F.SilkS")
		)
		(fp_line
			(start 1.2954 0.635)
			(end -1.2954 0.635)
			(stroke
				(width 0.1524)
				(type default)
			)
			(layer "F.SilkS")
		)
		(fp_poly
			(pts
				(xy -0.9144 0.508) (xy -0.9144 0.3556) (xy -1.143 0.3556) (xy -1.143 -0.3556) (xy -0.9144 -0.3556)
				(xy -0.9144 -0.508) (xy 0.9144 -0.508) (xy 0.9144 -0.3556) (xy 1.143 -0.3556) (xy 1.143 0.3556)
				(xy 0.9144 0.3556) (xy 0.9144 0.508)
			)
			(stroke
				(width 0)
				(type default)
			)
			(fill no)
			(layer "F.CrtYd")
		)
		(pad "1" smd rect
			(at 0.7366 0 180)
			(size 0.7112 0.8128)
			(layers "F.Cu" "F.Mask" "F.Paste")
			(net "BMC_NODE1_GFX_GREEN")
		)
		(pad "2" smd rect
			(at -0.7366 0 180)
			(size 0.7112 0.8128)
			(layers "F.Cu" "F.Mask" "F.Paste")
			(net "CRT_G_L")
		)
	)
)
